# S9S_MB_2U (Grand Teton) — schematic netlist excerpt (pin names and nets, part order shuffled) for the footprints in the layout excerpt that follows; sources: Cadence DE-HDL packaged netlist, KiCad conversion of 03242023_DA0F0TMBIJ0_F0T_Motherboard_J_brd_V01_OCP.brd

PC2947  Q_CAP  2.2UF 10V 10% X6S  pkg C0402  page 275 : A = PVCCFA_EHV_CPU0_PVCC ; B = GND
PC2216  Q_CAP  6800PF 50V 10% X7R  pkg C0402  page 192 : A = P3V3_E1S_GATE_0 ; B = GND
C1564  Q_CAP_DIFFBUS  DIFF BUS_0.22UF 6.3V 20% X6S  pkg C0201  page 175 : \1\ = P5E_CPU0_PE4_TX_C_DN<7> ; \2\ = P5E_CPU0_PE4_TX_DN<7>

(kicad_pcb
	(version 20260206)
	(generator "pcbnew")
	(generator_version "10.0")
	(general
		(thickness 1.6)
		(legacy_teardrops no)
	)
	(paper "A4")
	(title_block
		(title "03242023_DA0F0TMBIJ0_F0T_Motherboard_J_brd_V01_OCP.brd")
		(comment 1 "Grand Teton / footprints 310-312 of 6105")
	)
	(layers
		(0 "F.Cu" signal "TOP")
		(4 "In1.Cu" signal "GND")
		(6 "In2.Cu" signal "IN1")
		(8 "In3.Cu" signal "GND1")
		(10 "In4.Cu" signal "IN2")
		(12 "In5.Cu" signal "GND2")
		(14 "In6.Cu" signal "IN3")
		(16 "In7.Cu" signal "GND3")
		(18 "In8.Cu" signal "VCC")
		(20 "In9.Cu" signal "VCC1")
		(22 "In10.Cu" signal "GND4")
		(24 "In11.Cu" signal "IN4")
		(26 "In12.Cu" signal "GND5")
		(28 "In13.Cu" signal "IN5")
		(30 "In14.Cu" signal "GND6")
		(32 "In15.Cu" signal "IN6")
		(34 "In16.Cu" signal "GND7")
		(2 "B.Cu" signal "BOTTOM")
		(9 "F.Adhes" user "F.Adhesive")
		(11 "B.Adhes" user "B.Adhesive")
		(13 "F.Paste" user "Package Geometry/Pastemask Top")
		(15 "B.Paste" user "Package Geometry/Pastemask Bottom")
		(5 "F.SilkS" user "Ref Des/Silkscreen Top")
		(7 "B.SilkS" user "Ref Des/Silkscreen Bottom")
		(1 "F.Mask" user "Board Geometry/Soldermask Top")
		(3 "B.Mask" user "Board Geometry/Soldermask Bottom")
		(17 "Dwgs.User" user "User.Drawings")
		(19 "Cmts.User" user "User.Comments")
		(21 "Eco1.User" user "User.Eco1")
		(23 "Eco2.User" user "User.Eco2")
		(25 "Edge.Cuts" user "Board Geometry/Outline")
		(27 "Margin" user)
		(31 "F.CrtYd" user "Package Geometry/Place Bound Top")
		(29 "B.CrtYd" user "Package Geometry/Place Bound Bottom")
		(35 "F.Fab" user "Ref Des/Assembly Top")
		(33 "B.Fab" user "Ref Des/Assembly Bottom")
	)
	(footprint ""
		(layer "F.Cu")
		(at 415.818828 -174.396654 180)
		(property "Reference" "PC2947"
			(at 0 0 180)
			(layer "F.SilkS")
			(hide yes)
			(effects
				(font
					(size 1.27 1.27)
				)
			)
		)
		(property "Value" ""
			(at 0 0 180)
			(layer "F.Fab")
			(effects
				(font
					(size 1.27 1.27)
				)
			)
		)
		(duplicate_pad_numbers_are_jumpers no)
		(fp_line
			(start 0.7874 0.4064)
			(end -0.7874 0.4064)
			(stroke
				(width 0.1524)
				(type default)
			)
			(layer "F.SilkS")
		)
		(fp_line
			(start 0.7874 -0.4064)
			(end 0.7874 0.4064)
			(stroke
				(width 0.1524)
				(type default)
			)
			(layer "F.SilkS")
		)
		(fp_line
			(start -0.7874 0.4064)
			(end -0.7874 -0.4064)
			(stroke
				(width 0.1524)
				(type default)
			)
			(layer "F.SilkS")
		)
		(fp_line
			(start -0.7874 -0.4064)
			(end 0.7874 -0.4064)
			(stroke
				(width 0.1524)
				(type default)
			)
			(layer "F.SilkS")
		)
		(fp_line
			(start 0.67945 0.3048)
			(end 0.120396 0.3048)
			(stroke
				(width 0.1)
				(type default)
			)
			(layer "F.Fab")
		)
		(fp_line
			(start 0.67945 -0.3048)
			(end 0.67945 0.3048)
			(stroke
				(width 0.1)
				(type default)
			)
			(layer "F.Fab")
		)
		(fp_line
			(start 0.12065 -0.2794)
			(end 0.12065 -0.3048)
			(stroke
				(width 0.1)
				(type default)
			)
			(layer "F.Fab")
		)
		(fp_line
			(start 0.12065 -0.3048)
			(end 0.67945 -0.3048)
			(stroke
				(width 0.1)
				(type default)
			)
			(layer "F.Fab")
		)
		(fp_line
			(start 0.120396 0.3048)
			(end 0.120396 0.2794)
			(stroke
				(width 0.1)
				(type default)
			)
			(layer "F.Fab")
		)
		(fp_line
			(start 0.120396 0.2794)
			(end -0.12065 0.2794)
			(stroke
				(width 0.1)
				(type default)
			)
			(layer "F.Fab")
		)
		(fp_line
			(start -0.12065 0.3048)
			(end -0.67945 0.3048)
			(stroke
				(width 0.1)
				(type default)
			)
			(layer "F.Fab")
		)
		(fp_line
			(start -0.12065 0.2794)
			(end -0.12065 0.3048)
			(stroke
				(width 0.1)
				(type default)
			)
			(layer "F.Fab")
		)
		(fp_line
			(start -0.12065 -0.2794)
			(end 0.12065 -0.2794)
			(stroke
				(width 0.1)
				(type default)
			)
			(layer "F.Fab")
		)
		(fp_line
			(start -0.12065 -0.305054)
			(end -0.12065 -0.2794)
			(stroke
				(width 0.1)
				(type default)
			)
			(layer "F.Fab")
		)
		(fp_line
			(start -0.67945 0.3048)
			(end -0.67945 -0.305054)
			(stroke
				(width 0.1)
				(type default)
			)
			(layer "F.Fab")
		)
		(fp_line
			(start -0.67945 -0.305054)
			(end -0.12065 -0.305054)
			(stroke
				(width 0.1)
				(type default)
			)
			(layer "F.Fab")
		)
		(pad "1" smd circle
			(at -0.40005 0 180)
			(size 0 0)
			(layers "F.Cu" "F.Mask" "F.Paste")
			(net "PVCCFA_EHV_CPU0_PVCC")
		)
		(pad "2" smd circle
			(at 0.40005 0 180)
			(size 0 0)
			(layers "F.Cu" "F.Mask" "F.Paste")
			(net "GND")
		)
	)
	(footprint ""
		(layer "F.Cu")
		(at 325.397368 -402.371052 -90)
		(property "Reference" "C1564"
			(at 0 0 270)
			(layer "F.SilkS")
			(hide yes)
			(effects
				(font
					(size 1.27 1.27)
				)
			)
		)
		(property "Value" ""
			(at 0 0 270)
			(layer "F.Fab")
			(effects
				(font
					(size 1.27 1.27)
				)
			)
		)
		(duplicate_pad_numbers_are_jumpers no)
		(fp_line
			(start -0.299974 0.150114)
			(end -0.299974 -0.150114)
			(stroke
				(width 0.1)
				(type default)
			)
			(layer "F.Fab")
		)
		(fp_line
			(start 0.299974 0.150114)
			(end -0.299974 0.150114)
			(stroke
				(width 0.1)
				(type default)
			)
			(layer "F.Fab")
		)
		(fp_line
			(start -0.299974 -0.150114)
			(end 0.299974 -0.150114)
			(stroke
				(width 0.1)
				(type default)
			)
			(layer "F.Fab")
		)
		(fp_line
			(start 0.299974 -0.150114)
			(end 0.299974 0.150114)
			(stroke
				(width 0.1)
				(type default)
			)
			(layer "F.Fab")
		)
		(pad "1" smd rect
			(at -0.2667 0 270)
			(size 0.3048 0.381)
			(layers "F.Cu" "F.Mask" "F.Paste")
			(net "P5E_CPU0_PE4_TX_C_DN<7>")
		)
		(pad "2" smd rect
			(at 0.2667 0 270)
			(size 0.3048 0.381)
			(layers "F.Cu" "F.Mask" "F.Paste")
			(net "P5E_CPU0_PE4_TX_DN<7>")
		)
	)
	(footprint ""
		(layer "F.Cu")
		(at 223.37141 -73.517506)
		(property "Reference" "PC2216"
			(at 0 0 0)
			(layer "F.SilkS")
			(hide yes)
			(effects
				(font
					(size 1.27 1.27)
				)
			)
		)
		(property "Value" ""
			(at 0 0 0)
			(layer "F.Fab")
			(effects
				(font
					(size 1.27 1.27)
				)
			)
		)
		(duplicate_pad_numbers_are_jumpers no)
		(fp_line
			(start -0.7874 -0.4064)
			(end 0.7874 -0.4064)
			(stroke
				(width 0.1524)
				(type default)
			)
			(layer "F.SilkS")
		)
		(fp_line
			(start -0.7874 0.4064)
			(end -0.7874 -0.4064)
			(stroke
				(width 0.1524)
				(type default)
			)
			(layer "F.SilkS")
		)
		(fp_line
			(start 0.7874 -0.4064)
			(end 0.7874 0.4064)
			(stroke
				(width 0.1524)
				(type default)
			)
			(layer "F.SilkS")
		)
		(fp_line
			(start 0.7874 0.4064)
			(end -0.7874 0.4064)
			(stroke
				(width 0.1524)
				(type default)
			)
			(layer "F.SilkS")
		)
		(fp_line
			(start -0.67945 -0.305054)
			(end -0.12065 -0.305054)
			(stroke
				(width 0.1)
				(type default)
			)
			(layer "F.Fab")
		)
		(fp_line
			(start -0.67945 0.3048)
			(end -0.67945 -0.305054)
			(stroke
				(width 0.1)
				(type default)
			)
			(layer "F.Fab")
		)
		(fp_line
			(start -0.12065 -0.305054)
			(end -0.12065 -0.2794)
			(stroke
				(width 0.1)
				(type default)
			)
			(layer "F.Fab")
		)
		(fp_line
			(start -0.12065 -0.2794)
			(end 0.12065 -0.2794)
			(stroke
				(width 0.1)
				(type default)
			)
			(layer "F.Fab")
		)
		(fp_line
			(start -0.12065 0.2794)
			(end -0.12065 0.3048)
			(stroke
				(width 0.1)
				(type default)
			)
			(layer "F.Fab")
		)
		(fp_line
			(start -0.12065 0.3048)
			(end -0.67945 0.3048)
			(stroke
				(width 0.1)
				(type default)
			)
			(layer "F.Fab")
		)
		(fp_line
			(start 0.120396 0.2794)
			(end -0.12065 0.2794)
			(stroke
				(width 0.1)
				(type default)
			)
			(layer "F.Fab")
		)
		(fp_line
			(start 0.120396 0.3048)
			(end 0.120396 0.2794)
			(stroke
				(width 0.1)
				(type default)
			)
			(layer "F.Fab")
		)
		(fp_line
			(start 0.12065 -0.3048)
			(end 0.67945 -0.3048)
			(stroke
				(width 0.1)
				(type default)
			)
			(layer "F.Fab")
		)
		(fp_line
			(start 0.12065 -0.2794)
			(end 0.12065 -0.3048)
			(stroke
				(width 0.1)
				(type default)
			)
			(layer "F.Fab")
		)
		(fp_line
			(start 0.67945 -0.3048)
			(end 0.67945 0.3048)
			(stroke
				(width 0.1)
				(type default)
			)
			(layer "F.Fab")
		)
		(fp_line
			(start 0.67945 0.3048)
			(end 0.120396 0.3048)
			(stroke
				(width 0.1)
				(type default)
			)
			(layer "F.Fab")
		)
		(pad "1" smd circle
			(at -0.40005 0)
			(size 0 0)
			(layers "F.Cu" "F.Mask" "F.Paste")
			(net "P3V3_E1S_GATE_0")
		)
		(pad "2" smd circle
			(at 0.40005 0)
			(size 0 0)
			(layers "F.Cu" "F.Mask" "F.Paste")
			(net "GND")
		)
	)
)
